(kicad_pcb
	(version 20260206)
	(generator "pcbnew")
	(generator_version "10.0")
	(general
		(thickness 1.6)
		(legacy_teardrops no)
	)
	(paper "A4")
	(title_block
		(title "Wiwynn_Tioga_Pass_MB.brd")
		(comment 1 "Tioga Pass / footprints 942-948 of 4770")
	)
	(layers
		(0 "F.Cu" signal "TOP")
		(4 "In1.Cu" signal "L2GND")
		(6 "In2.Cu" signal "L3")
		(8 "In3.Cu" signal "L4GND")
		(10 "In4.Cu" signal "L5")
		(12 "In5.Cu" signal "L6GND")
		(14 "In6.Cu" signal "L7VCC")
		(16 "In7.Cu" signal "L8VCC")
		(18 "In8.Cu" signal "L9GND")
		(20 "In9.Cu" signal "L10")
		(22 "In10.Cu" signal "L11GND")
		(24 "In11.Cu" signal "L12")
		(26 "In12.Cu" signal "L13GND")
		(2 "B.Cu" signal "BOTTOM")
		(9 "F.Adhes" user "F.Adhesive")
		(11 "B.Adhes" user "B.Adhesive")
		(13 "F.Paste" user "Package Geometry/Pastemask Top")
		(15 "B.Paste" user "Package Geometry/Pastemask Bottom")
		(5 "F.SilkS" user "Ref Des/Silkscreen Top")
		(7 "B.SilkS" user "Ref Des/Silkscreen Bottom")
		(1 "F.Mask" user "Board Geometry/Soldermask Top")
		(3 "B.Mask" user "Board Geometry/Soldermask Bottom")
		(17 "Dwgs.User" user "User.Drawings")
		(19 "Cmts.User" user "User.Comments")
		(21 "Eco1.User" user "User.Eco1")
		(23 "Eco2.User" user "User.Eco2")
		(25 "Edge.Cuts" user "Board Geometry/Outline")
		(27 "Margin" user)
		(31 "F.CrtYd" user "Package Geometry/Place Bound Top")
		(29 "B.CrtYd" user "Package Geometry/Place Bound Bottom")
		(35 "F.Fab" user "Ref Des/Assembly Top")
		(33 "B.Fab" user "Ref Des/Assembly Bottom")
	)
	(footprint ""
		(layer "F.Cu")
		(at 206.248 -102.616 90)
		(property "Reference" "R4C4"
			(at 0 0 90)
			(layer "F.SilkS")
			(hide yes)
			(effects
				(font
					(size 1.27 1.27)
				)
			)
		)
		(property "Value" ""
			(at 0 0 90)
			(layer "F.Fab")
			(effects
				(font
					(size 1.27 1.27)
				)
			)
		)
		(duplicate_pad_numbers_are_jumpers no)
		(fp_poly
			(pts
				(xy -0.2794 -0.1016) (xy 0.2794 -0.1016) (xy 0.2794 0.9906) (xy -0.2794 0.9906)
			)
			(stroke
				(width 0)
				(type default)
			)
			(fill no)
			(layer "F.CrtYd")
		)
		(fp_line
			(start 0.2794 -0.1016)
			(end -0.2794 -0.1016)
			(stroke
				(width 0.1)
				(type default)
			)
			(layer "F.Fab")
		)
		(fp_line
			(start -0.2794 -0.1016)
			(end -0.2794 0.9906)
			(stroke
				(width 0.1)
				(type default)
			)
			(layer "F.Fab")
		)
		(fp_line
			(start 0.2794 0.9906)
			(end 0.2794 -0.1016)
			(stroke
				(width 0.1)
				(type default)
			)
			(layer "F.Fab")
		)
		(fp_line
			(start -0.2794 0.9906)
			(end 0.2794 0.9906)
			(stroke
				(width 0.1)
				(type default)
			)
			(layer "F.Fab")
		)
		(pad "1" smd rect
			(at 0 0 90)
			(size 0.508 0.508)
			(layers "F.Cu" "F.Mask" "F.Paste")
			(net "VSENSE_PVSA_CPU0_P")
		)
		(pad "2" smd rect
			(at 0 0.889 90)
			(size 0.508 0.508)
			(layers "F.Cu" "F.Mask" "F.Paste")
			(net "VSENSE_PVSA_CPU0_SKT_VSEN")
		)
		(zone
			(layer "F.Cu")
			(hatch none 0.5)
			(connect_pads
				(clearance 0)
			)
			(min_thickness 0.25)
			(keepout
				(tracks allowed)
				(vias not_allowed)
				(pads allowed)
				(copperpour not_allowed)
				(footprints allowed)
			)
			(placement
				(enabled no)
				(sheetname "")
			)
			(fill
				(thermal_gap 0.5)
				(thermal_bridge_width 0.5)
				(island_removal_mode 0)
			)
			(polygon
				(pts
					(xy 206.502 -102.362) (xy 206.502 -102.87) (xy 206.883 -102.87) (xy 206.883 -102.362)
				)
			)
		)
		(zone
			(layer "F.Cu")
			(hatch none 0.5)
			(connect_pads
				(clearance 0)
			)
			(min_thickness 0.25)
			(keepout
				(tracks not_allowed)
				(vias allowed)
				(pads allowed)
				(copperpour not_allowed)
				(footprints allowed)
			)
			(placement
				(enabled no)
				(sheetname "")
			)
			(fill
				(thermal_gap 0.5)
				(thermal_bridge_width 0.5)
				(island_removal_mode 0)
			)
			(polygon
				(pts
					(xy 206.883 -102.362) (xy 206.883 -102.87) (xy 206.502 -102.87) (xy 206.502 -102.362)
				)
			)
		)
	)
	(footprint ""
		(layer "F.Cu")
		(at 412.085282 -125.863604)
		(property "Reference" "R8B15"
			(at 0 0 0)
			(layer "F.SilkS")
			(hide yes)
			(effects
				(font
					(size 1.27 1.27)
				)
			)
		)
		(property "Value" ""
			(at 0 0 0)
			(layer "F.Fab")
			(effects
				(font
					(size 1.27 1.27)
				)
			)
		)
		(duplicate_pad_numbers_are_jumpers no)
		(fp_poly
			(pts
				(xy -0.2794 -0.1016) (xy 0.2794 -0.1016) (xy 0.2794 0.9906) (xy -0.2794 0.9906)
			)
			(stroke
				(width 0)
				(type default)
			)
			(fill no)
			(layer "F.CrtYd")
		)
		(fp_line
			(start -0.2794 -0.1016)
			(end -0.2794 0.9906)
			(stroke
				(width 0.1)
				(type default)
			)
			(layer "F.Fab")
		)
		(fp_line
			(start -0.2794 0.9906)
			(end 0.2794 0.9906)
			(stroke
				(width 0.1)
				(type default)
			)
			(layer "F.Fab")
		)
		(fp_line
			(start 0.2794 -0.1016)
			(end -0.2794 -0.1016)
			(stroke
				(width 0.1)
				(type default)
			)
			(layer "F.Fab")
		)
		(fp_line
			(start 0.2794 0.9906)
			(end 0.2794 -0.1016)
			(stroke
				(width 0.1)
				(type default)
			)
			(layer "F.Fab")
		)
		(pad "1" smd rect
			(at 0 0)
			(size 0.508 0.508)
			(layers "F.Cu" "F.Mask" "F.Paste")
			(net "VSENSE_P1V05_PCH_STBY_AVSP")
		)
		(pad "2" smd rect
			(at 0 0.889)
			(size 0.508 0.508)
			(layers "F.Cu" "F.Mask" "F.Paste")
			(net "VSENSE_P1V05_PCH_STBY_AVSN")
		)
		(zone
			(layer "F.Cu")
			(hatch none 0.5)
			(connect_pads
				(clearance 0)
			)
			(min_thickness 0.25)
			(keepout
				(tracks allowed)
				(vias not_allowed)
				(pads allowed)
				(copperpour not_allowed)
				(footprints allowed)
			)
			(placement
				(enabled no)
				(sheetname "")
			)
			(fill
				(thermal_gap 0.5)
				(thermal_bridge_width 0.5)
				(island_removal_mode 0)
			)
			(polygon
				(pts
					(xy 411.831282 -125.609604) (xy 412.339282 -125.609604) (xy 412.339282 -125.228604) (xy 411.831282 -125.228604)
				)
			)
		)
		(zone
			(layer "F.Cu")
			(hatch none 0.5)
			(connect_pads
				(clearance 0)
			)
			(min_thickness 0.25)
			(keepout
				(tracks not_allowed)
				(vias allowed)
				(pads allowed)
				(copperpour not_allowed)
				(footprints allowed)
			)
			(placement
				(enabled no)
				(sheetname "")
			)
			(fill
				(thermal_gap 0.5)
				(thermal_bridge_width 0.5)
				(island_removal_mode 0)
			)
			(polygon
				(pts
					(xy 411.831282 -125.228604) (xy 412.339282 -125.228604) (xy 412.339282 -125.609604) (xy 411.831282 -125.609604)
				)
			)
		)
	)
	(footprint ""
		(layer "F.Cu")
		(at 363.87024 -139.30757 90)
		(property "Reference" "R7A11"
			(at 0 0 90)
			(layer "F.SilkS")
			(hide yes)
			(effects
				(font
					(size 1.27 1.27)
				)
			)
		)
		(property "Value" ""
			(at 0 0 90)
			(layer "F.Fab")
			(effects
				(font
					(size 1.27 1.27)
				)
			)
		)
		(duplicate_pad_numbers_are_jumpers no)
		(fp_rect
			(start -0.2794 -0.1016)
			(end 0.2794 0.9906)
			(stroke
				(width 0)
				(type default)
			)
			(fill no)
			(layer "F.CrtYd")
		)
		(fp_line
			(start 0.2794 -0.1016)
			(end -0.2794 -0.1016)
			(stroke
				(width 0.1)
				(type default)
			)
			(layer "F.Fab")
		)
		(fp_line
			(start -0.2794 -0.1016)
			(end -0.2794 0.9906)
			(stroke
				(width 0.1)
				(type default)
			)
			(layer "F.Fab")
		)
		(fp_line
			(start 0.2794 0.9906)
			(end 0.2794 -0.1016)
			(stroke
				(width 0.1)
				(type default)
			)
			(layer "F.Fab")
		)
		(fp_line
			(start -0.2794 0.9906)
			(end 0.2794 0.9906)
			(stroke
				(width 0.1)
				(type default)
			)
			(layer "F.Fab")
		)
		(pad "1" smd rect
			(at 0 0 90)
			(size 0.508 0.508)
			(layers "F.Cu" "F.Mask" "F.Paste")
			(net "SVID_ALERT_PVDDQ_DEF")
		)
		(pad "2" smd rect
			(at 0 0.889 90)
			(size 0.508 0.508)
			(layers "F.Cu" "F.Mask" "F.Paste")
			(net "SVID_ALERT1_CPU0_R_N")
		)
		(zone
			(layer "F.Cu")
			(hatch none 0.5)
			(connect_pads
				(clearance 0)
			)
			(min_thickness 0.25)
			(keepout
				(tracks allowed)
				(vias not_allowed)
				(pads allowed)
				(copperpour not_allowed)
				(footprints allowed)
			)
			(placement
				(enabled no)
				(sheetname "")
			)
			(fill
				(thermal_gap 0.5)
				(thermal_bridge_width 0.5)
				(island_removal_mode 0)
			)
			(polygon
				(pts
					(xy 364.12424 -139.05357) (xy 364.50524 -139.05357) (xy 364.50524 -139.56157) (xy 364.12424 -139.56157)
				)
			)
		)
		(zone
			(layer "F.Cu")
			(hatch none 0.5)
			(connect_pads
				(clearance 0)
			)
			(min_thickness 0.25)
			(keepout
				(tracks not_allowed)
				(vias allowed)
				(pads allowed)
				(copperpour not_allowed)
				(footprints allowed)
			)
			(placement
				(enabled no)
				(sheetname "")
			)
			(fill
				(thermal_gap 0.5)
				(thermal_bridge_width 0.5)
				(island_removal_mode 0)
			)
			(polygon
				(pts
					(xy 364.12424 -139.05357) (xy 364.50524 -139.05357) (xy 364.50524 -139.56157) (xy 364.12424 -139.56157)
				)
			)
		)
	)
	(footprint ""
		(layer "F.Cu")
		(at 423.421048 3.679952 180)
		(property "Reference" "XBT8G1"
			(at 7.65556 5.53847 0)
			(unlocked yes)
			(layer "F.SilkS")
			(effects
				(font
					(size 0.7874 0.5842)
					(thickness 0.1524)
				)
				(justify left)
			)
		)
		(property "Value" ""
			(at 0 0 180)
			(layer "F.Fab")
			(effects
				(font
					(size 1.27 1.27)
				)
			)
		)
		(duplicate_pad_numbers_are_jumpers no)
		(fp_line
			(start 16.774922 4.824984)
			(end -6.774942 4.824984)
			(stroke
				(width 0.1524)
				(type default)
			)
			(layer "F.SilkS")
		)
		(fp_line
			(start 16.774922 -1.225042)
			(end 16.774922 4.824984)
			(stroke
				(width 0.1524)
				(type default)
			)
			(layer "F.SilkS")
		)
		(fp_line
			(start -2.2098 -3.2512)
			(end -2.2098 -1.9812)
			(stroke
				(width 0.1524)
				(type default)
			)
			(layer "F.SilkS")
		)
		(fp_line
			(start -2.8448 -2.6162)
			(end -1.5748 -2.6162)
			(stroke
				(width 0.1524)
				(type default)
			)
			(layer "F.SilkS")
		)
		(fp_line
			(start -6.774942 4.824984)
			(end -6.774942 -1.225042)
			(stroke
				(width 0.1524)
				(type default)
			)
			(layer "F.SilkS")
		)
		(fp_line
			(start -6.774942 -1.225042)
			(end 16.774922 -1.225042)
			(stroke
				(width 0.1524)
				(type default)
			)
			(layer "F.SilkS")
		)
		(fp_poly
			(pts
				(xy -6.774942 -1.225042) (xy -6.774942 4.824984) (xy 16.774922 4.824984) (xy 16.774922 -1.225042)
			)
			(stroke
				(width 0)
				(type default)
			)
			(fill no)
			(layer "F.CrtYd")
		)
		(fp_line
			(start 16.774922 4.824984)
			(end 16.774922 -1.225042)
			(stroke
				(width 0.1)
				(type default)
			)
			(layer "F.Fab")
		)
		(fp_line
			(start 16.774922 -1.225042)
			(end -6.774942 -1.225042)
			(stroke
				(width 0.1)
				(type default)
			)
			(layer "F.Fab")
		)
		(fp_line
			(start -2.2098 -3.2512)
			(end -2.2098 -1.9812)
			(stroke
				(width 0.1)
				(type default)
			)
			(layer "F.Fab")
		)
		(fp_line
			(start -2.8448 -2.6162)
			(end -1.5748 -2.6162)
			(stroke
				(width 0.1)
				(type default)
			)
			(layer "F.Fab")
		)
		(fp_line
			(start -6.774942 4.824984)
			(end 16.774922 4.824984)
			(stroke
				(width 0.1)
				(type default)
			)
			(layer "F.Fab")
		)
		(fp_line
			(start -6.774942 -1.225042)
			(end -6.774942 4.824984)
			(stroke
				(width 0.1)
				(type default)
			)
			(layer "F.Fab")
		)
		(pad "1" thru_hole rect
			(at 0 0 180)
			(size 1.3716 1.3716)
			(drill 0.9906)
			(layers "*.Cu" "*.Mask")
			(remove_unused_layers no)
			(net "P3V_BAT_SOURCE")
			(clearance 0.127)
			(thermal_gap 0.127)
			(padstack
				(mode front_inner_back)
				(layer "Inner"
					(shape circle)
					(size 1.3716 1.3716)
					(clearance 0.127)
				)
				(layer "B.Cu"
					(shape rect)
					(size 1.3716 1.3716)
					(clearance 0.127)
				)
			)
		)
		(pad "2" thru_hole circle
			(at 9.99998 0 180)
			(size 1.3716 1.3716)
			(drill 0.9906)
			(layers "*.Cu" "*.Mask")
			(remove_unused_layers no)
			(net "P3V_BAT_SOURCE")
			(clearance 0.127)
			(thermal_gap 0.127)
		)
		(pad "3" thru_hole circle
			(at 4.99999 3.599942 180)
			(size 1.3716 1.3716)
			(drill 0.9906)
			(layers "*.Cu" "*.Mask")
			(remove_unused_layers no)
			(net "GND")
			(clearance 0.127)
			(thermal_gap 0.127)
		)
	)
	(footprint ""
		(layer "F.Cu")
		(at 171.983146 -146.429222 180)
		(property "Reference" "EU4A2"
			(at 0.787146 -1.904492 0)
			(unlocked yes)
			(layer "F.SilkS")
			(effects
				(font
					(size 0.7874 0.5842)
					(thickness 0.1524)
				)
				(justify left)
			)
		)
		(property "Value" ""
			(at 0 0 180)
			(layer "F.Fab")
			(effects
				(font
					(size 1.27 1.27)
				)
			)
		)
		(duplicate_pad_numbers_are_jumpers no)
		(fp_circle
			(center -0.835152 -0.417322)
			(end -0.962152 -0.417322)
			(stroke
				(width 0.254)
				(type default)
			)
			(fill no)
			(layer "F.SilkS")
		)
		(fp_poly
			(pts
				(xy -0.064516 -1.0922) (xy -0.064516 -0.3302) (xy 0.697484 -1.0922)
			)
			(stroke
				(width 0)
				(type default)
			)
			(fill yes)
			(layer "F.SilkS")
		)
		(fp_rect
			(start 0.597408 2.295398)
			(end 2.273808 -0.295402)
			(stroke
				(width 0)
				(type default)
			)
			(fill yes)
			(layer "F.Paste")
		)
		(fp_rect
			(start -0.064516 2.500122)
			(end 2.935478 -0.500126)
			(stroke
				(width 0)
				(type default)
			)
			(fill no)
			(layer "F.CrtYd")
		)
		(fp_line
			(start 2.935478 2.500122)
			(end -0.064516 2.500122)
			(stroke
				(width 0.1)
				(type default)
			)
			(layer "F.Fab")
		)
		(fp_line
			(start 2.935478 -0.500126)
			(end 2.935478 2.500122)
			(stroke
				(width 0.1)
				(type default)
			)
			(layer "F.Fab")
		)
		(fp_line
			(start -0.064516 2.500122)
			(end -0.064516 -0.500126)
			(stroke
				(width 0.1)
				(type default)
			)
			(layer "F.Fab")
		)
		(fp_line
			(start -0.064516 -0.500126)
			(end 2.935478 -0.500126)
			(stroke
				(width 0.1)
				(type default)
			)
			(layer "F.Fab")
		)
		(fp_circle
			(center -0.835152 -0.417322)
			(end -0.962152 -0.417322)
			(stroke
				(width 0.254)
				(type default)
			)
			(fill no)
			(layer "F.Fab")
		)
		(pad "1" smd rect
			(at 0 0 180)
			(size 0.6858 0.3048)
			(layers "F.Cu" "F.Mask" "F.Paste")
			(net "VR_PVTT_KLM_VREF")
		)
		(pad "2" smd rect
			(at 0 0.500126 180)
			(size 0.6858 0.3048)
			(layers "F.Cu" "F.Mask" "F.Paste")
			(net "VR_PVTT_KLM_BIAS")
		)
		(pad "3" smd rect
			(at 0 0.999998 180)
			(size 0.6858 0.3048)
			(layers "F.Cu" "F.Mask" "F.Paste")
			(net "GND")
		)
		(pad "4" smd rect
			(at 0 1.500124 180)
			(size 0.6858 0.3048)
			(layers "F.Cu" "F.Mask" "F.Paste")
			(net "VSENSE_PVDDQ_KLM_VTT")
		)
		(pad "5" smd rect
			(at 0 1.999996 180)
			(size 0.6858 0.3048)
			(layers "F.Cu" "F.Mask" "F.Paste")
			(net "PWRGD_PVTT_KLM_CPU1_R")
		)
		(pad "6" smd rect
			(at 2.871216 1.999996 180)
			(size 0.6858 0.3048)
			(layers "F.Cu" "F.Mask" "F.Paste")
			(net "VR_PVTT_KLM_SNS")
		)
		(pad "7" smd rect
			(at 2.871216 1.500124 180)
			(size 0.6858 0.3048)
			(layers "F.Cu" "F.Mask" "F.Paste")
			(net "FM_PVTT_KLM_EN_R")
		)
		(pad "8" smd rect
			(at 2.871216 0.999998 180)
			(size 0.6858 0.3048)
			(layers "F.Cu" "F.Mask" "F.Paste")
			(net "GND")
		)
		(pad "9" smd rect
			(at 2.871216 0.500126 180)
			(size 0.6858 0.3048)
			(layers "F.Cu" "F.Mask" "F.Paste")
			(net "PVTT_KLM")
		)
		(pad "10" smd rect
			(at 2.871216 0 180)
			(size 0.6858 0.3048)
			(layers "F.Cu" "F.Mask" "F.Paste")
			(net "PVDDQ_KLM")
		)
		(pad "11" smd rect
			(at 1.435608 0.999998 180)
			(size 1.6764 2.5908)
			(layers "F.Cu" "F.Mask" "F.Paste")
			(net "GND")
		)
	)
	(footprint ""
		(layer "F.Cu")
		(at 14.097 13.2715 -90)
		(property "Reference" "T1P32"
			(at 0 0 270)
			(layer "F.SilkS")
			(hide yes)
			(effects
				(font
					(size 1.27 1.27)
				)
			)
		)
		(property "Value" "*"
			(at 0 -3.44805 270)
			(unlocked yes)
			(layer "F.Fab")
			(hide yes)
			(effects
				(font
					(size 0.889 0.889)
					(thickness 0.1524)
				)
			)
		)
		(property "Device Type" "TPAD-SE-2P-GP_DISCRET-GA1-TPADA"
			(at 0 -4.97205 270)
			(unlocked yes)
			(layer "F.Fab")
			(hide yes)
			(effects
				(font
					(size 0.889 0.889)
					(thickness 0.1524)
				)
			)
		)
		(duplicate_pad_numbers_are_jumpers no)
		(fp_line
			(start -1.016 2.286)
			(end -1.016 -2.286)
			(stroke
				(width 0.1524)
				(type default)
			)
			(layer "F.SilkS")
		)
		(fp_line
			(start 1.016 2.286)
			(end -1.016 2.286)
			(stroke
				(width 0.1524)
				(type default)
			)
			(layer "F.SilkS")
		)
		(fp_line
			(start -1.016 -2.286)
			(end 1.016 -2.286)
			(stroke
				(width 0.1524)
				(type default)
			)
			(layer "F.SilkS")
		)
		(fp_line
			(start 1.016 -2.286)
			(end 1.016 2.286)
			(stroke
				(width 0.1524)
				(type default)
			)
			(layer "F.SilkS")
		)
		(fp_rect
			(start -1.27 2.54)
			(end 1.27 -2.54)
			(stroke
				(width 0)
				(type default)
			)
			(fill no)
			(layer "F.CrtYd")
		)
		(fp_rect
			(start -1.27 2.54)
			(end 1.27 -2.54)
			(stroke
				(width 0)
				(type default)
			)
			(fill no)
			(layer "F.Fab")
		)
		(pad "1" thru_hole circle
			(at 0 -1.27 270)
			(size 1.524 1.524)
			(drill 0.9144)
			(layers "*.Cu" "*.Mask")
			(remove_unused_layers no)
			(net "L3_50OHM_6INCH")
			(clearance -0.0508)
			(thermal_gap 0.127)
			(padstack
				(mode front_inner_back)
				(layer "Inner"
					(shape circle)
					(size 1.1684 1.1684)
					(clearance 0.127)
				)
				(layer "B.Cu"
					(shape circle)
					(size 1.524 1.524)
					(clearance -0.0508)
				)
			)
		)
		(pad "GND1" thru_hole rect
			(at 0 1.27 270)
			(size 1.524 1.524)
			(drill 0.9144)
			(layers "*.Cu" "*.Mask")
			(remove_unused_layers no)
			(net "GND")
			(clearance -0.0508)
			(thermal_gap 0.127)
			(padstack
				(mode front_inner_back)
				(layer "Inner"
					(shape circle)
					(size 1.1684 1.1684)
					(clearance 0.127)
				)
				(layer "B.Cu"
					(shape rect)
					(size 1.524 1.524)
					(clearance -0.0508)
				)
			)
		)
	)
	(footprint ""
		(layer "F.Cu")
		(at 460.2226 -30.734)
		(property "Reference" "R1U2"
			(at 0 0 0)
			(layer "F.SilkS")
			(hide yes)
			(effects
				(font
					(size 1.27 1.27)
				)
			)
		)
		(property "Value" ""
			(at 0 0 0)
			(layer "F.Fab")
			(effects
				(font
					(size 1.27 1.27)
				)
			)
		)
		(duplicate_pad_numbers_are_jumpers no)
		(fp_poly
			(pts
				(xy -0.2794 -0.1016) (xy 0.2794 -0.1016) (xy 0.2794 0.9906) (xy -0.2794 0.9906)
			)
			(stroke
				(width 0)
				(type default)
			)
			(fill no)
			(layer "F.CrtYd")
		)
		(fp_line
			(start -0.2794 -0.1016)
			(end -0.2794 0.9906)
			(stroke
				(width 0.1)
				(type default)
			)
			(layer "F.Fab")
		)
		(fp_line
			(start -0.2794 0.9906)
			(end 0.2794 0.9906)
			(stroke
				(width 0.1)
				(type default)
			)
			(layer "F.Fab")
		)
		(fp_line
			(start 0.2794 -0.1016)
			(end -0.2794 -0.1016)
			(stroke
				(width 0.1)
				(type default)
			)
			(layer "F.Fab")
		)
		(fp_line
			(start 0.2794 0.9906)
			(end 0.2794 -0.1016)
			(stroke
				(width 0.1)
				(type default)
			)
			(layer "F.Fab")
		)
		(pad "1" smd rect
			(at 0 0)
			(size 0.508 0.508)
			(layers "F.Cu" "F.Mask" "F.Paste")
			(net "FAN_TACH2")
		)
		(pad "2" smd rect
			(at 0 0.889)
			(size 0.508 0.508)
			(layers "F.Cu" "F.Mask" "F.Paste")
			(net "GND")
		)
		(zone
			(layer "F.Cu")
			(hatch none 0.5)
			(connect_pads
				(clearance 0)
			)
			(min_thickness 0.25)
			(keepout
				(tracks allowed)
				(vias not_allowed)
				(pads allowed)
				(copperpour not_allowed)
				(footprints allowed)
			)
			(placement
				(enabled no)
				(sheetname "")
			)
			(fill
				(thermal_gap 0.5)
				(thermal_bridge_width 0.5)
				(island_removal_mode 0)
			)
			(polygon
				(pts
					(xy 459.9686 -30.48) (xy 460.4766 -30.48) (xy 460.4766 -30.099) (xy 459.9686 -30.099)
				)
			)
		)
		(zone
			(layer "F.Cu")
			(hatch none 0.5)
			(connect_pads
				(clearance 0)
			)
			(min_thickness 0.25)
			(keepout
				(tracks not_allowed)
				(vias allowed)
				(pads allowed)
				(copperpour not_allowed)
				(footprints allowed)
			)
			(placement
				(enabled no)
				(sheetname "")
			)
			(fill
				(thermal_gap 0.5)
				(thermal_bridge_width 0.5)
				(island_removal_mode 0)
			)
			(polygon
				(pts
					(xy 459.9686 -30.099) (xy 460.4766 -30.099) (xy 460.4766 -30.48) (xy 459.9686 -30.48)
				)
			)
		)
	)
)
